# BASEBOARD_FAB2 (Tioga Pass) — schematic netlist excerpt (pin names and nets, part order shuffled) for the footprints in the layout excerpt that follows; sources: Cadence DE-HDL packaged netlist, KiCad conversion of Wiwynn_Tioga_Pass_MB.brd

C9P1  CAP  10UF 16V 10% X6S  pkg 0805  page 208 : A = VR_FET_SW_P12V_STBY_PVCCIN_CPU1 ; B = GND
R25W2  120R2F-GP  1%  pkg RCL_GP  page 151 : \1\ = GND ; \2\ = BMC_M_ODT
C5G90  CAP_A  22.0UF 4V 20% X6S  pkg 0603V  page 243 : A = PVDDQ_GHJ ; B = GND

(kicad_pcb
	(version 20260206)
	(generator "pcbnew")
	(generator_version "10.0")
	(general
		(thickness 1.6)
		(legacy_teardrops no)
	)
	(paper "A4")
	(title_block
		(title "Wiwynn_Tioga_Pass_MB.brd")
		(comment 1 "Tioga Pass / footprints 2396-2398 of 4770")
	)
	(layers
		(0 "F.Cu" signal "TOP")
		(4 "In1.Cu" signal "L2GND")
		(6 "In2.Cu" signal "L3")
		(8 "In3.Cu" signal "L4GND")
		(10 "In4.Cu" signal "L5")
		(12 "In5.Cu" signal "L6GND")
		(14 "In6.Cu" signal "L7VCC")
		(16 "In7.Cu" signal "L8VCC")
		(18 "In8.Cu" signal "L9GND")
		(20 "In9.Cu" signal "L10")
		(22 "In10.Cu" signal "L11GND")
		(24 "In11.Cu" signal "L12")
		(26 "In12.Cu" signal "L13GND")
		(2 "B.Cu" signal "BOTTOM")
		(9 "F.Adhes" user "F.Adhesive")
		(11 "B.Adhes" user "B.Adhesive")
		(13 "F.Paste" user "Package Geometry/Pastemask Top")
		(15 "B.Paste" user "Package Geometry/Pastemask Bottom")
		(5 "F.SilkS" user "Ref Des/Silkscreen Top")
		(7 "B.SilkS" user "Ref Des/Silkscreen Bottom")
		(1 "F.Mask" user "Board Geometry/Soldermask Top")
		(3 "B.Mask" user "Board Geometry/Soldermask Bottom")
		(17 "Dwgs.User" user "User.Drawings")
		(19 "Cmts.User" user "User.Comments")
		(21 "Eco1.User" user "User.Eco1")
		(23 "Eco2.User" user "User.Eco2")
		(25 "Edge.Cuts" user "Board Geometry/Outline")
		(27 "Margin" user)
		(31 "F.CrtYd" user "Package Geometry/Place Bound Top")
		(29 "B.CrtYd" user "Package Geometry/Place Bound Bottom")
		(35 "F.Fab" user "Ref Des/Assembly Top")
		(33 "B.Fab" user "Ref Des/Assembly Bottom")
	)
	(footprint ""
		(layer "B.Cu")
		(at 446.381632 -33.5915 90)
		(property "Reference" "R25W2"
			(at 0 0 90)
			(layer "B.SilkS")
			(hide yes)
			(effects
				(font
					(size 1.27 1.27)
				)
				(justify mirror)
			)
		)
		(property "Value" "*"
			(at -0.064008 -4.108196 90)
			(unlocked yes)
			(layer "B.Fab")
			(hide yes)
			(effects
				(font
					(size 1.27 1.016)
					(thickness 0.1524)
				)
				(justify mirror)
			)
		)
		(property "Device Type" "120R2F-GP_RCL_GP-120R2F-GP,64.A"
			(at -0.064008 -5.632196 90)
			(unlocked yes)
			(layer "B.Fab")
			(hide yes)
			(effects
				(font
					(size 1.27 1.016)
					(thickness 0.1524)
				)
				(justify mirror)
			)
		)
		(duplicate_pad_numbers_are_jumpers no)
		(fp_line
			(start 0.508 -0.9398)
			(end 0.508 0.9398)
			(stroke
				(width 0.1524)
				(type default)
			)
			(layer "B.SilkS")
		)
		(fp_line
			(start -0.508 -0.9398)
			(end 0.508 -0.9398)
			(stroke
				(width 0.1524)
				(type default)
			)
			(layer "B.SilkS")
		)
		(fp_rect
			(start 0.508 0.9398)
			(end -0.508 -0.9398)
			(stroke
				(width 0)
				(type default)
			)
			(fill no)
			(layer "B.CrtYd")
		)
		(fp_rect
			(start 0.508 0.9398)
			(end -0.508 -0.9398)
			(stroke
				(width 0)
				(type default)
			)
			(fill no)
			(layer "B.Fab")
		)
		(pad "1" smd custom
			(at 0 -0.4445 270)
			(size 0.1397 0.1397)
			(layers "B.Cu" "B.Mask" "B.Paste")
			(net "GND")
			(options
				(clearance outline)
				(anchor circle)
			)
			(primitives
				(gr_poly
					(pts
						(arc
							(start -0.1778 0.2794)
							(mid -0.249642 0.249642)
							(end -0.2794 0.1778)
						)
						(arc
							(start -0.2794 -0.1778)
							(mid -0.249642 -0.249642)
							(end -0.1778 -0.2794)
						)
						(arc
							(start 0.1778 -0.2794)
							(mid 0.249642 -0.249642)
							(end 0.2794 -0.1778)
						)
						(arc
							(start 0.2794 0.1778)
							(mid 0.249642 0.249642)
							(end 0.1778 0.2794)
						)
					)
					(width 0)
					(fill yes)
				)
			)
		)
		(pad "2" smd custom
			(at 0 0.4445 270)
			(size 0.1397 0.1397)
			(layers "B.Cu" "B.Mask" "B.Paste")
			(net "BMC_M_ODT")
			(options
				(clearance outline)
				(anchor circle)
			)
			(primitives
				(gr_poly
					(pts
						(arc
							(start -0.1778 0.2794)
							(mid -0.249642 0.249642)
							(end -0.2794 0.1778)
						)
						(arc
							(start -0.2794 -0.1778)
							(mid -0.249642 -0.249642)
							(end -0.1778 -0.2794)
						)
						(arc
							(start 0.1778 -0.2794)
							(mid 0.249642 -0.249642)
							(end 0.2794 -0.1778)
						)
						(arc
							(start 0.2794 0.1778)
							(mid 0.249642 0.249642)
							(end 0.1778 0.2794)
						)
					)
					(width 0)
					(fill yes)
				)
			)
		)
	)
	(footprint ""
		(layer "B.Cu")
		(at 32.832802 -82.681064 90)
		(property "Reference" "C9P1"
			(at 0 0 90)
			(layer "B.SilkS")
			(hide yes)
			(effects
				(font
					(size 1.27 1.27)
				)
				(justify mirror)
			)
		)
		(property "Value" ""
			(at 0 0 90)
			(layer "B.Fab")
			(effects
				(font
					(size 1.27 1.27)
				)
				(justify mirror)
			)
		)
		(duplicate_pad_numbers_are_jumpers no)
		(fp_poly
			(pts
				(xy 0.7239 -0.2159) (xy -0.7239 -0.2159) (xy -0.7239 1.9939) (xy 0.7239 1.9939)
			)
			(stroke
				(width 0)
				(type default)
			)
			(fill no)
			(layer "B.CrtYd")
		)
		(fp_line
			(start 0.7239 -0.2159)
			(end 0.7239 1.9939)
			(stroke
				(width 0.1)
				(type default)
			)
			(layer "B.Fab")
		)
		(fp_line
			(start -0.7239 -0.2159)
			(end 0.7239 -0.2159)
			(stroke
				(width 0.1)
				(type default)
			)
			(layer "B.Fab")
		)
		(fp_line
			(start 0.7239 1.9939)
			(end -0.7239 1.9939)
			(stroke
				(width 0.1)
				(type default)
			)
			(layer "B.Fab")
		)
		(fp_line
			(start -0.7239 1.9939)
			(end -0.7239 -0.2159)
			(stroke
				(width 0.1)
				(type default)
			)
			(layer "B.Fab")
		)
		(pad "1" smd rect
			(at 0 0 270)
			(size 1.27 1.016)
			(layers "B.Cu" "B.Mask" "B.Paste")
			(net "VR_FET_SW_P12V_STBY_PVCCIN_CPU1")
		)
		(pad "2" smd rect
			(at 0 1.778 270)
			(size 1.27 1.016)
			(layers "B.Cu" "B.Mask" "B.Paste")
			(net "GND")
		)
		(zone
			(layer "B.Cu")
			(hatch none 0.5)
			(connect_pads
				(clearance 0)
			)
			(min_thickness 0.25)
			(keepout
				(tracks not_allowed)
				(vias allowed)
				(pads allowed)
				(copperpour not_allowed)
				(footprints allowed)
			)
			(placement
				(enabled no)
				(sheetname "")
			)
			(fill
				(thermal_gap 0.5)
				(thermal_bridge_width 0.5)
				(island_removal_mode 0)
			)
			(polygon
				(pts
					(xy 33.340802 -83.316064) (xy 33.340802 -82.046064) (xy 34.102802 -82.046064) (xy 34.102802 -83.316064)
				)
			)
		)
	)
	(footprint ""
		(layer "B.Cu")
		(at 104.5591 -3.3528 90)
		(property "Reference" "C5G90"
			(at -1.14681 0.76708 180)
			(unlocked yes)
			(layer "B.SilkS")
			(effects
				(font
					(size 0.7874 0.5842)
					(thickness 0.1524)
				)
				(justify mirror)
			)
		)
		(property "Value" ""
			(at 0 0 90)
			(layer "B.Fab")
			(effects
				(font
					(size 1.27 1.27)
				)
				(justify mirror)
			)
		)
		(duplicate_pad_numbers_are_jumpers no)
		(fp_rect
			(start -0.4953 -0.2032)
			(end 0.4953 1.6002)
			(stroke
				(width 0)
				(type default)
			)
			(fill no)
			(layer "B.CrtYd")
		)
		(fp_line
			(start 0.4953 -0.2032)
			(end -0.4953 -0.2032)
			(stroke
				(width 0.1)
				(type default)
			)
			(layer "B.Fab")
		)
		(fp_line
			(start -0.4953 -0.2032)
			(end -0.4953 1.6002)
			(stroke
				(width 0.1)
				(type default)
			)
			(layer "B.Fab")
		)
		(fp_line
			(start 0.4953 1.6002)
			(end 0.4953 -0.2032)
			(stroke
				(width 0.1)
				(type default)
			)
			(layer "B.Fab")
		)
		(fp_line
			(start -0.4953 1.6002)
			(end 0.4953 1.6002)
			(stroke
				(width 0.1)
				(type default)
			)
			(layer "B.Fab")
		)
		(pad "1" smd rect
			(at 0 0 270)
			(size 0.762 0.889)
			(layers "B.Cu" "B.Mask" "B.Paste")
			(net "PVDDQ_GHJ")
		)
		(pad "2" smd rect
			(at 0 1.397 270)
			(size 0.762 0.889)
			(layers "B.Cu" "B.Mask" "B.Paste")
			(net "GND")
		)
		(zone
			(layer "B.Cu")
			(hatch none 0.5)
			(connect_pads
				(clearance 0)
			)
			(min_thickness 0.25)
			(keepout
				(tracks not_allowed)
				(vias allowed)
				(pads allowed)
				(copperpour not_allowed)
				(footprints allowed)
			)
			(placement
				(enabled no)
				(sheetname "")
			)
			(fill
				(thermal_gap 0.5)
				(thermal_bridge_width 0.5)
				(island_removal_mode 0)
			)
			(polygon
				(pts
					(xy 105.0036 -2.9718) (xy 105.5116 -2.9718) (xy 105.5116 -3.7338) (xy 105.0036 -3.7338)
				)
			)
		)
	)
)
